(kicad_pcb
	(version 20260206)
	(generator "pcbnew")
	(generator_version "10.0")
	(general
		(thickness 1.6)
		(legacy_teardrops no)
	)
	(paper "A4")
	(title_block
		(title "03242023_DA0F0TMBIJ0_F0T_Motherboard_J_brd_V01_OCP.brd")
		(comment 1 "Grand Teton / footprints 534-536 of 6105")
	)
	(layers
		(0 "F.Cu" signal "TOP")
		(4 "In1.Cu" signal "GND")
		(6 "In2.Cu" signal "IN1")
		(8 "In3.Cu" signal "GND1")
		(10 "In4.Cu" signal "IN2")
		(12 "In5.Cu" signal "GND2")
		(14 "In6.Cu" signal "IN3")
		(16 "In7.Cu" signal "GND3")
		(18 "In8.Cu" signal "VCC")
		(20 "In9.Cu" signal "VCC1")
		(22 "In10.Cu" signal "GND4")
		(24 "In11.Cu" signal "IN4")
		(26 "In12.Cu" signal "GND5")
		(28 "In13.Cu" signal "IN5")
		(30 "In14.Cu" signal "GND6")
		(32 "In15.Cu" signal "IN6")
		(34 "In16.Cu" signal "GND7")
		(2 "B.Cu" signal "BOTTOM")
		(9 "F.Adhes" user "F.Adhesive")
		(11 "B.Adhes" user "B.Adhesive")
		(13 "F.Paste" user "Package Geometry/Pastemask Top")
		(15 "B.Paste" user "Package Geometry/Pastemask Bottom")
		(5 "F.SilkS" user "Ref Des/Silkscreen Top")
		(7 "B.SilkS" user "Ref Des/Silkscreen Bottom")
		(1 "F.Mask" user "Board Geometry/Soldermask Top")
		(3 "B.Mask" user "Board Geometry/Soldermask Bottom")
		(17 "Dwgs.User" user "User.Drawings")
		(19 "Cmts.User" user "User.Comments")
		(21 "Eco1.User" user "User.Eco1")
		(23 "Eco2.User" user "User.Eco2")
		(25 "Edge.Cuts" user "Board Geometry/Outline")
		(27 "Margin" user)
		(31 "F.CrtYd" user "Package Geometry/Place Bound Top")
		(29 "B.CrtYd" user "Package Geometry/Place Bound Bottom")
		(35 "F.Fab" user "Ref Des/Assembly Top")
		(33 "B.Fab" user "Ref Des/Assembly Bottom")
	)
	(footprint ""
		(layer "F.Cu")
		(at 444.733172 -32.173418 -90)
		(property "Reference" "R3834"
			(at 0 0 270)
			(layer "F.SilkS")
			(hide yes)
			(effects
				(font
					(size 1.27 1.27)
				)
			)
		)
		(property "Value" ""
			(at 0 0 270)
			(layer "F.Fab")
			(effects
				(font
					(size 1.27 1.27)
				)
			)
		)
		(duplicate_pad_numbers_are_jumpers no)
		(fp_line
			(start -0.7874 0.4064)
			(end -0.7874 -0.4064)
			(stroke
				(width 0.1524)
				(type default)
			)
			(layer "F.SilkS")
		)
		(fp_line
			(start 0.7874 0.4064)
			(end -0.7874 0.4064)
			(stroke
				(width 0.1524)
				(type default)
			)
			(layer "F.SilkS")
		)
		(fp_line
			(start -0.7874 -0.4064)
			(end 0.7874 -0.4064)
			(stroke
				(width 0.1524)
				(type default)
			)
			(layer "F.SilkS")
		)
		(fp_line
			(start 0.7874 -0.4064)
			(end 0.7874 0.4064)
			(stroke
				(width 0.1524)
				(type default)
			)
			(layer "F.SilkS")
		)
		(fp_line
			(start -0.67945 0.3048)
			(end -0.67945 -0.305054)
			(stroke
				(width 0.1)
				(type default)
			)
			(layer "F.Fab")
		)
		(fp_line
			(start -0.12065 0.3048)
			(end -0.67945 0.3048)
			(stroke
				(width 0.1)
				(type default)
			)
			(layer "F.Fab")
		)
		(fp_line
			(start 0.120396 0.3048)
			(end 0.120396 0.2794)
			(stroke
				(width 0.1)
				(type default)
			)
			(layer "F.Fab")
		)
		(fp_line
			(start 0.67945 0.3048)
			(end 0.120396 0.3048)
			(stroke
				(width 0.1)
				(type default)
			)
			(layer "F.Fab")
		)
		(fp_line
			(start -0.12065 0.2794)
			(end -0.12065 0.3048)
			(stroke
				(width 0.1)
				(type default)
			)
			(layer "F.Fab")
		)
		(fp_line
			(start 0.120396 0.2794)
			(end -0.12065 0.2794)
			(stroke
				(width 0.1)
				(type default)
			)
			(layer "F.Fab")
		)
		(fp_line
			(start -0.12065 -0.2794)
			(end 0.12065 -0.2794)
			(stroke
				(width 0.1)
				(type default)
			)
			(layer "F.Fab")
		)
		(fp_line
			(start 0.12065 -0.2794)
			(end 0.12065 -0.3048)
			(stroke
				(width 0.1)
				(type default)
			)
			(layer "F.Fab")
		)
		(fp_line
			(start 0.12065 -0.3048)
			(end 0.67945 -0.3048)
			(stroke
				(width 0.1)
				(type default)
			)
			(layer "F.Fab")
		)
		(fp_line
			(start 0.67945 -0.3048)
			(end 0.67945 0.3048)
			(stroke
				(width 0.1)
				(type default)
			)
			(layer "F.Fab")
		)
		(fp_line
			(start -0.67945 -0.305054)
			(end -0.12065 -0.305054)
			(stroke
				(width 0.1)
				(type default)
			)
			(layer "F.Fab")
		)
		(fp_line
			(start -0.12065 -0.305054)
			(end -0.12065 -0.2794)
			(stroke
				(width 0.1)
				(type default)
			)
			(layer "F.Fab")
		)
		(pad "1" smd circle
			(at -0.40005 0 270)
			(size 0 0)
			(layers "F.Cu" "F.Mask" "F.Paste")
			(net "HP_LVC3_OCP_V3_1_EN")
		)
		(pad "2" smd circle
			(at 0.40005 0 270)
			(size 0 0)
			(layers "F.Cu" "F.Mask" "F.Paste")
			(net "P12V_OCP_EN_1_R2")
		)
	)
	(footprint ""
		(layer "F.Cu")
		(at 506.378972 -342.873838)
		(property "Reference" "DB2"
			(at 2.71399 1.386586 90)
			(unlocked yes)
			(layer "F.SilkS")
			(effects
				(font
					(size 0.7874 0.5842)
					(thickness 0.1524)
				)
				(justify left)
			)
		)
		(property "Value" ""
			(at 0 0 0)
			(layer "F.Fab")
			(effects
				(font
					(size 1.27 1.27)
				)
			)
		)
		(duplicate_pad_numbers_are_jumpers no)
		(fp_line
			(start -3.330702 -4.771136)
			(end 3.330702 -4.771136)
			(stroke
				(width 0.1524)
				(type default)
			)
			(layer "F.SilkS")
		)
		(fp_line
			(start 0 4.011168)
			(end -3.330702 -4.771136)
			(stroke
				(width 0.1524)
				(type default)
			)
			(layer "F.SilkS")
		)
		(fp_line
			(start 3.330702 -4.771136)
			(end 0 4.011168)
			(stroke
				(width 0.1524)
				(type default)
			)
			(layer "F.SilkS")
		)
		(fp_line
			(start -3.330702 -4.771136)
			(end 3.330702 -4.771136)
			(stroke
				(width 0.1)
				(type default)
			)
			(layer "F.Fab")
		)
		(fp_line
			(start 0 4.011168)
			(end -3.330702 -4.771136)
			(stroke
				(width 0.1)
				(type default)
			)
			(layer "F.Fab")
		)
		(fp_line
			(start 3.330702 -4.771136)
			(end 0 4.011168)
			(stroke
				(width 0.1)
				(type default)
			)
			(layer "F.Fab")
		)
		(pad "1" thru_hole circle
			(at 0 0)
			(size 2.159 2.159)
			(drill 1.7018)
			(layers "*.Cu" "*.Mask")
			(remove_unused_layers no)
			(net "T1_GND")
			(clearance 0.0254)
			(thermal_gap 0.0254)
		)
		(pad "2" thru_hole circle
			(at -1.27 -3.348736)
			(size 2.159 2.159)
			(drill 1.7018)
			(layers "*.Cu" "*.Mask")
			(remove_unused_layers no)
			(net "TDR_SE_40_OHM_IN1")
			(clearance 0.0254)
			(thermal_gap 0.0254)
		)
		(pad "3" thru_hole circle
			(at 1.27 -3.348736)
			(size 2.159 2.159)
			(drill 1.7018)
			(layers "*.Cu" "*.Mask")
			(remove_unused_layers no)
			(net "TDR_SE_40_OHM_IN1")
			(clearance 0.0254)
			(thermal_gap 0.0254)
		)
	)
	(footprint ""
		(layer "F.Cu")
		(at 103.306372 -363.873034)
		(property "Reference" "R2521"
			(at 0 0 0)
			(layer "F.SilkS")
			(hide yes)
			(effects
				(font
					(size 1.27 1.27)
				)
			)
		)
		(property "Value" ""
			(at 0 0 0)
			(layer "F.Fab")
			(effects
				(font
					(size 1.27 1.27)
				)
			)
		)
		(duplicate_pad_numbers_are_jumpers no)
		(fp_line
			(start -0.7874 -0.4064)
			(end 0.7874 -0.4064)
			(stroke
				(width 0.1524)
				(type default)
			)
			(layer "F.SilkS")
		)
		(fp_line
			(start -0.7874 0.4064)
			(end -0.7874 -0.4064)
			(stroke
				(width 0.1524)
				(type default)
			)
			(layer "F.SilkS")
		)
		(fp_line
			(start 0.7874 -0.4064)
			(end 0.7874 0.4064)
			(stroke
				(width 0.1524)
				(type default)
			)
			(layer "F.SilkS")
		)
		(fp_line
			(start 0.7874 0.4064)
			(end -0.7874 0.4064)
			(stroke
				(width 0.1524)
				(type default)
			)
			(layer "F.SilkS")
		)
		(fp_line
			(start -0.67945 -0.305054)
			(end -0.12065 -0.305054)
			(stroke
				(width 0.1)
				(type default)
			)
			(layer "F.Fab")
		)
		(fp_line
			(start -0.67945 0.3048)
			(end -0.67945 -0.305054)
			(stroke
				(width 0.1)
				(type default)
			)
			(layer "F.Fab")
		)
		(fp_line
			(start -0.12065 -0.305054)
			(end -0.12065 -0.2794)
			(stroke
				(width 0.1)
				(type default)
			)
			(layer "F.Fab")
		)
		(fp_line
			(start -0.12065 -0.2794)
			(end 0.12065 -0.2794)
			(stroke
				(width 0.1)
				(type default)
			)
			(layer "F.Fab")
		)
		(fp_line
			(start -0.12065 0.2794)
			(end -0.12065 0.3048)
			(stroke
				(width 0.1)
				(type default)
			)
			(layer "F.Fab")
		)
		(fp_line
			(start -0.12065 0.3048)
			(end -0.67945 0.3048)
			(stroke
				(width 0.1)
				(type default)
			)
			(layer "F.Fab")
		)
		(fp_line
			(start 0.120396 0.2794)
			(end -0.12065 0.2794)
			(stroke
				(width 0.1)
				(type default)
			)
			(layer "F.Fab")
		)
		(fp_line
			(start 0.120396 0.3048)
			(end 0.120396 0.2794)
			(stroke
				(width 0.1)
				(type default)
			)
			(layer "F.Fab")
		)
		(fp_line
			(start 0.12065 -0.3048)
			(end 0.67945 -0.3048)
			(stroke
				(width 0.1)
				(type default)
			)
			(layer "F.Fab")
		)
		(fp_line
			(start 0.12065 -0.2794)
			(end 0.12065 -0.3048)
			(stroke
				(width 0.1)
				(type default)
			)
			(layer "F.Fab")
		)
		(fp_line
			(start 0.67945 -0.3048)
			(end 0.67945 0.3048)
			(stroke
				(width 0.1)
				(type default)
			)
			(layer "F.Fab")
		)
		(fp_line
			(start 0.67945 0.3048)
			(end 0.120396 0.3048)
			(stroke
				(width 0.1)
				(type default)
			)
			(layer "F.Fab")
		)
		(pad "1" smd circle
			(at -0.40005 0)
			(size 0 0)
			(layers "F.Cu" "F.Mask" "F.Paste")
			(net "SMB_VR_3V3AUX_SDA_R3")
		)
		(pad "2" smd circle
			(at 0.40005 0)
			(size 0 0)
			(layers "F.Cu" "F.Mask" "F.Paste")
			(net "SMB_DIO_PVCCIN_CPU1")
		)
	)
)
